(kicad_pcb
	(version 20260206)
	(generator "pcbnew")
	(generator_version "10.0")
	(general
		(thickness 1.6)
		(legacy_teardrops no)
	)
	(paper "A4")
	(title_block
		(title "Wiwynn_Tioga_Pass_MB.brd")
		(comment 1 "Tioga Pass / footprints 1804-1811 of 4770")
	)
	(layers
		(0 "F.Cu" signal "TOP")
		(4 "In1.Cu" signal "L2GND")
		(6 "In2.Cu" signal "L3")
		(8 "In3.Cu" signal "L4GND")
		(10 "In4.Cu" signal "L5")
		(12 "In5.Cu" signal "L6GND")
		(14 "In6.Cu" signal "L7VCC")
		(16 "In7.Cu" signal "L8VCC")
		(18 "In8.Cu" signal "L9GND")
		(20 "In9.Cu" signal "L10")
		(22 "In10.Cu" signal "L11GND")
		(24 "In11.Cu" signal "L12")
		(26 "In12.Cu" signal "L13GND")
		(2 "B.Cu" signal "BOTTOM")
		(9 "F.Adhes" user "F.Adhesive")
		(11 "B.Adhes" user "B.Adhesive")
		(13 "F.Paste" user "Package Geometry/Pastemask Top")
		(15 "B.Paste" user "Package Geometry/Pastemask Bottom")
		(5 "F.SilkS" user "Ref Des/Silkscreen Top")
		(7 "B.SilkS" user "Ref Des/Silkscreen Bottom")
		(1 "F.Mask" user "Board Geometry/Soldermask Top")
		(3 "B.Mask" user "Board Geometry/Soldermask Bottom")
		(17 "Dwgs.User" user "User.Drawings")
		(19 "Cmts.User" user "User.Comments")
		(21 "Eco1.User" user "User.Eco1")
		(23 "Eco2.User" user "User.Eco2")
		(25 "Edge.Cuts" user "Board Geometry/Outline")
		(27 "Margin" user)
		(31 "F.CrtYd" user "Package Geometry/Place Bound Top")
		(29 "B.CrtYd" user "Package Geometry/Place Bound Bottom")
		(35 "F.Fab" user "Ref Des/Assembly Top")
		(33 "B.Fab" user "Ref Des/Assembly Bottom")
	)
	(footprint ""
		(layer "F.Cu")
		(at 268.165072 -73.318116)
		(property "Reference" "C5D47"
			(at 0 0 0)
			(layer "F.SilkS")
			(hide yes)
			(effects
				(font
					(size 1.27 1.27)
				)
			)
		)
		(property "Value" ""
			(at 0 0 0)
			(layer "F.Fab")
			(effects
				(font
					(size 1.27 1.27)
				)
			)
		)
		(duplicate_pad_numbers_are_jumpers no)
		(fp_poly
			(pts
				(xy -0.4953 -0.2032) (xy 0.4953 -0.2032) (xy 0.4953 1.6002) (xy -0.4953 1.6002)
			)
			(stroke
				(width 0)
				(type default)
			)
			(fill no)
			(layer "F.CrtYd")
		)
		(fp_line
			(start -0.4953 -0.2032)
			(end 0.4953 -0.2032)
			(stroke
				(width 0.1)
				(type default)
			)
			(layer "F.Fab")
		)
		(fp_line
			(start -0.4953 1.6002)
			(end -0.4953 -0.2032)
			(stroke
				(width 0.1)
				(type default)
			)
			(layer "F.Fab")
		)
		(fp_line
			(start 0.4953 -0.2032)
			(end 0.4953 1.6002)
			(stroke
				(width 0.1)
				(type default)
			)
			(layer "F.Fab")
		)
		(fp_line
			(start 0.4953 1.6002)
			(end -0.4953 1.6002)
			(stroke
				(width 0.1)
				(type default)
			)
			(layer "F.Fab")
		)
		(pad "1" smd rect
			(at 0 0)
			(size 0.762 0.889)
			(layers "F.Cu" "F.Mask" "F.Paste")
			(net "PVCCIN_CPU0")
		)
		(pad "2" smd rect
			(at 0 1.397)
			(size 0.762 0.889)
			(layers "F.Cu" "F.Mask" "F.Paste")
			(net "GND")
		)
		(zone
			(layer "F.Cu")
			(hatch none 0.5)
			(connect_pads
				(clearance 0)
			)
			(min_thickness 0.25)
			(keepout
				(tracks not_allowed)
				(vias allowed)
				(pads allowed)
				(copperpour not_allowed)
				(footprints allowed)
			)
			(placement
				(enabled no)
				(sheetname "")
			)
			(fill
				(thermal_gap 0.5)
				(thermal_bridge_width 0.5)
				(island_removal_mode 0)
			)
			(polygon
				(pts
					(xy 267.784072 -72.873616) (xy 268.546072 -72.873616) (xy 268.546072 -72.365616) (xy 267.784072 -72.365616)
				)
			)
		)
	)
	(footprint ""
		(layer "F.Cu")
		(at 258.208272 -73.318116)
		(property "Reference" "C5D39"
			(at 0 0 0)
			(layer "F.SilkS")
			(hide yes)
			(effects
				(font
					(size 1.27 1.27)
				)
			)
		)
		(property "Value" ""
			(at 0 0 0)
			(layer "F.Fab")
			(effects
				(font
					(size 1.27 1.27)
				)
			)
		)
		(duplicate_pad_numbers_are_jumpers no)
		(fp_poly
			(pts
				(xy -0.4953 -0.2032) (xy 0.4953 -0.2032) (xy 0.4953 1.6002) (xy -0.4953 1.6002)
			)
			(stroke
				(width 0)
				(type default)
			)
			(fill no)
			(layer "F.CrtYd")
		)
		(fp_line
			(start -0.4953 -0.2032)
			(end 0.4953 -0.2032)
			(stroke
				(width 0.1)
				(type default)
			)
			(layer "F.Fab")
		)
		(fp_line
			(start -0.4953 1.6002)
			(end -0.4953 -0.2032)
			(stroke
				(width 0.1)
				(type default)
			)
			(layer "F.Fab")
		)
		(fp_line
			(start 0.4953 -0.2032)
			(end 0.4953 1.6002)
			(stroke
				(width 0.1)
				(type default)
			)
			(layer "F.Fab")
		)
		(fp_line
			(start 0.4953 1.6002)
			(end -0.4953 1.6002)
			(stroke
				(width 0.1)
				(type default)
			)
			(layer "F.Fab")
		)
		(pad "1" smd rect
			(at 0 0)
			(size 0.762 0.889)
			(layers "F.Cu" "F.Mask" "F.Paste")
			(net "PVCCIN_CPU0")
		)
		(pad "2" smd rect
			(at 0 1.397)
			(size 0.762 0.889)
			(layers "F.Cu" "F.Mask" "F.Paste")
			(net "GND")
		)
		(zone
			(layer "F.Cu")
			(hatch none 0.5)
			(connect_pads
				(clearance 0)
			)
			(min_thickness 0.25)
			(keepout
				(tracks not_allowed)
				(vias allowed)
				(pads allowed)
				(copperpour not_allowed)
				(footprints allowed)
			)
			(placement
				(enabled no)
				(sheetname "")
			)
			(fill
				(thermal_gap 0.5)
				(thermal_bridge_width 0.5)
				(island_removal_mode 0)
			)
			(polygon
				(pts
					(xy 257.827272 -72.873616) (xy 258.589272 -72.873616) (xy 258.589272 -72.365616) (xy 257.827272 -72.365616)
				)
			)
		)
	)
	(footprint ""
		(layer "F.Cu")
		(at 21.29028 -121.43232 -90)
		(property "Reference" "CR1B1"
			(at 3.22199 1.60528 0)
			(unlocked yes)
			(layer "F.SilkS")
			(effects
				(font
					(size 0.7874 0.5842)
					(thickness 0.1524)
				)
				(justify left)
			)
		)
		(property "Value" ""
			(at 0 0 270)
			(layer "F.Fab")
			(effects
				(font
					(size 1.27 1.27)
				)
			)
		)
		(duplicate_pad_numbers_are_jumpers no)
		(fp_line
			(start -1.335278 2.576068)
			(end -1.335278 1.664462)
			(stroke
				(width 0.1524)
				(type default)
			)
			(layer "F.SilkS")
		)
		(fp_line
			(start -1.8161 1.664462)
			(end -1.335278 0.831596)
			(stroke
				(width 0.1524)
				(type default)
			)
			(layer "F.SilkS")
		)
		(fp_line
			(start -1.335278 1.664462)
			(end -1.8161 1.664462)
			(stroke
				(width 0.1524)
				(type default)
			)
			(layer "F.SilkS")
		)
		(fp_line
			(start -0.854456 1.664462)
			(end -1.335278 1.664462)
			(stroke
				(width 0.1524)
				(type default)
			)
			(layer "F.SilkS")
		)
		(fp_line
			(start -1.335278 0.831596)
			(end -0.854456 1.664462)
			(stroke
				(width 0.1524)
				(type default)
			)
			(layer "F.SilkS")
		)
		(fp_line
			(start -0.854456 0.831596)
			(end -1.8161 0.831596)
			(stroke
				(width 0.1524)
				(type default)
			)
			(layer "F.SilkS")
		)
		(fp_line
			(start -1.335278 -0.291846)
			(end -1.335278 0.831596)
			(stroke
				(width 0.1524)
				(type default)
			)
			(layer "F.SilkS")
		)
		(fp_rect
			(start 0.67437 2.04216)
			(end -0.67437 0.24384)
			(stroke
				(width 0)
				(type default)
			)
			(fill no)
			(layer "F.CrtYd")
		)
		(fp_line
			(start -0.67437 2.04216)
			(end 0.67437 2.04216)
			(stroke
				(width 0.1)
				(type default)
			)
			(layer "F.Fab")
		)
		(fp_line
			(start 0.67437 2.04216)
			(end 0.67437 0.24384)
			(stroke
				(width 0.1)
				(type default)
			)
			(layer "F.Fab")
		)
		(fp_line
			(start -1.8161 1.664462)
			(end -1.335278 0.831596)
			(stroke
				(width 0.1)
				(type default)
			)
			(layer "F.Fab")
		)
		(fp_line
			(start -1.335278 1.664462)
			(end -1.335278 2.576068)
			(stroke
				(width 0.1)
				(type default)
			)
			(layer "F.Fab")
		)
		(fp_line
			(start -0.854456 1.664462)
			(end -1.8161 1.664462)
			(stroke
				(width 0.1)
				(type default)
			)
			(layer "F.Fab")
		)
		(fp_line
			(start -1.335278 0.831596)
			(end -0.854456 1.664462)
			(stroke
				(width 0.1)
				(type default)
			)
			(layer "F.Fab")
		)
		(fp_line
			(start -1.335278 0.831596)
			(end -1.335278 -0.291846)
			(stroke
				(width 0.1)
				(type default)
			)
			(layer "F.Fab")
		)
		(fp_line
			(start -0.854456 0.831596)
			(end -1.8161 0.831596)
			(stroke
				(width 0.1)
				(type default)
			)
			(layer "F.Fab")
		)
		(fp_line
			(start -0.67437 0.24384)
			(end -0.67437 2.04216)
			(stroke
				(width 0.1)
				(type default)
			)
			(layer "F.Fab")
		)
		(fp_line
			(start 0.67437 0.24384)
			(end -0.67437 0.24384)
			(stroke
				(width 0.1)
				(type default)
			)
			(layer "F.Fab")
		)
		(pad "1" smd rect
			(at 0 0 270)
			(size 0.4064 1.016)
			(layers "F.Cu" "F.Mask" "F.Paste")
			(net "P5V_STBY")
		)
		(pad "2" smd rect
			(at 0 2.286 270)
			(size 0.4064 1.016)
			(layers "F.Cu" "F.Mask" "F.Paste")
			(net "FAN_PWM_OUT_SYS1_R")
		)
	)
	(footprint ""
		(layer "F.Cu")
		(at 442.368686 -43.254676)
		(property "Reference" "C25W18"
			(at 0 0 0)
			(layer "F.SilkS")
			(hide yes)
			(effects
				(font
					(size 1.27 1.27)
				)
			)
		)
		(property "Value" "*"
			(at 0 -2.9337 0)
			(unlocked yes)
			(layer "F.Fab")
			(hide yes)
			(effects
				(font
					(size 1.27 1.016)
					(thickness 0.1524)
				)
			)
		)
		(property "Device Type" "SC1U16V3KX-2GP_SMD-BCG-SC1U16VA"
			(at 0 -4.4577 0)
			(unlocked yes)
			(layer "F.Fab")
			(hide yes)
			(effects
				(font
					(size 1.27 1.016)
					(thickness 0.1524)
				)
			)
		)
		(duplicate_pad_numbers_are_jumpers no)
		(fp_line
			(start 0.508 0)
			(end -0.508 0)
			(stroke
				(width 0.2032)
				(type default)
			)
			(layer "F.SilkS")
		)
		(fp_rect
			(start -0.5842 1.3335)
			(end 0.5842 -1.3335)
			(stroke
				(width 0)
				(type default)
			)
			(fill no)
			(layer "F.CrtYd")
		)
		(fp_rect
			(start -0.5842 1.3335)
			(end 0.5842 -1.3335)
			(stroke
				(width 0)
				(type default)
			)
			(fill no)
			(layer "F.Fab")
		)
		(pad "1" smd custom
			(at 0 -0.762)
			(size 0.2159 0.2159)
			(layers "F.Cu" "F.Mask" "F.Paste")
			(net "P1V2_AUX_BMC")
			(options
				(clearance outline)
				(anchor circle)
			)
			(primitives
				(gr_poly
					(pts
						(arc
							(start -0.3302 -0.4318)
							(mid -0.402042 -0.402042)
							(end -0.4318 -0.3302)
						)
						(arc
							(start -0.4318 0.3302)
							(mid -0.402042 0.402042)
							(end -0.3302 0.4318)
						)
						(arc
							(start 0.3302 0.4318)
							(mid 0.402042 0.402042)
							(end 0.4318 0.3302)
						)
						(arc
							(start 0.4318 -0.3302)
							(mid 0.402042 -0.402042)
							(end 0.3302 -0.4318)
						)
					)
					(width 0)
					(fill yes)
				)
			)
		)
		(pad "2" smd custom
			(at 0 0.762)
			(size 0.2159 0.2159)
			(layers "F.Cu" "F.Mask" "F.Paste")
			(net "GND")
			(options
				(clearance outline)
				(anchor circle)
			)
			(primitives
				(gr_poly
					(pts
						(arc
							(start -0.3302 -0.4318)
							(mid -0.402042 -0.402042)
							(end -0.4318 -0.3302)
						)
						(arc
							(start -0.4318 0.3302)
							(mid -0.402042 0.402042)
							(end -0.3302 0.4318)
						)
						(arc
							(start 0.3302 0.4318)
							(mid 0.402042 0.402042)
							(end 0.4318 0.3302)
						)
						(arc
							(start 0.4318 -0.3302)
							(mid 0.402042 -0.402042)
							(end 0.3302 -0.4318)
						)
					)
					(width 0)
					(fill yes)
				)
			)
		)
	)
	(footprint ""
		(layer "F.Cu")
		(at -0.277622 -118.636034 90)
		(property "Reference" "C10W5"
			(at -0.8382 -0.67818 90)
			(unlocked yes)
			(layer "F.SilkS")
			(effects
				(font
					(size 0.4064 0.254)
					(thickness 0.1524)
				)
				(justify left)
			)
		)
		(property "Value" ""
			(at 0 0 90)
			(layer "F.Fab")
			(effects
				(font
					(size 1.27 1.27)
				)
			)
		)
		(duplicate_pad_numbers_are_jumpers no)
		(fp_poly
			(pts
				(xy 0.3048 -0.1016) (xy 0.3048 0.9906) (xy -0.3048 0.9906) (xy -0.3048 -0.1016)
			)
			(stroke
				(width 0)
				(type default)
			)
			(fill no)
			(layer "F.CrtYd")
		)
		(fp_line
			(start 0.3048 -0.1016)
			(end -0.3048 -0.1016)
			(stroke
				(width 0.1)
				(type default)
			)
			(layer "F.Fab")
		)
		(fp_line
			(start -0.3048 -0.1016)
			(end -0.3048 0.9906)
			(stroke
				(width 0.1)
				(type default)
			)
			(layer "F.Fab")
		)
		(fp_line
			(start 0.3048 0.9906)
			(end 0.3048 -0.1016)
			(stroke
				(width 0.1)
				(type default)
			)
			(layer "F.Fab")
		)
		(fp_line
			(start -0.3048 0.9906)
			(end 0.3048 0.9906)
			(stroke
				(width 0.1)
				(type default)
			)
			(layer "F.Fab")
		)
		(pad "1" smd rect
			(at 0 0 90)
			(size 0.508 0.508)
			(layers "F.Cu" "F.Mask" "F.Paste")
			(net "PUMP_TACH1")
		)
		(pad "2" smd rect
			(at 0 0.889 90)
			(size 0.508 0.508)
			(layers "F.Cu" "F.Mask" "F.Paste")
			(net "GND")
		)
		(zone
			(layer "F.Cu")
			(hatch none 0.5)
			(connect_pads
				(clearance 0)
			)
			(min_thickness 0.25)
			(keepout
				(tracks allowed)
				(vias not_allowed)
				(pads allowed)
				(copperpour not_allowed)
				(footprints allowed)
			)
			(placement
				(enabled no)
				(sheetname "")
			)
			(fill
				(thermal_gap 0.5)
				(thermal_bridge_width 0.5)
				(island_removal_mode 0)
			)
			(polygon
				(pts
					(xy -0.023622 -118.382034) (xy -0.023622 -118.890034) (xy 0.357378 -118.890034) (xy 0.357378 -118.382034)
				)
			)
		)
		(zone
			(layer "F.Cu")
			(hatch none 0.5)
			(connect_pads
				(clearance 0)
			)
			(min_thickness 0.25)
			(keepout
				(tracks not_allowed)
				(vias allowed)
				(pads allowed)
				(copperpour not_allowed)
				(footprints allowed)
			)
			(placement
				(enabled no)
				(sheetname "")
			)
			(fill
				(thermal_gap 0.5)
				(thermal_bridge_width 0.5)
				(island_removal_mode 0)
			)
			(polygon
				(pts
					(xy 0.357378 -118.382034) (xy 0.357378 -118.890034) (xy -0.023622 -118.890034) (xy -0.023622 -118.382034)
				)
			)
		)
	)
	(footprint ""
		(layer "F.Cu")
		(at 116.3066 -73.787 90)
		(property "Reference" "R3D15"
			(at 0 0 90)
			(layer "F.SilkS")
			(hide yes)
			(effects
				(font
					(size 1.27 1.27)
				)
			)
		)
		(property "Value" ""
			(at 0 0 90)
			(layer "F.Fab")
			(effects
				(font
					(size 1.27 1.27)
				)
			)
		)
		(duplicate_pad_numbers_are_jumpers no)
		(fp_poly
			(pts
				(xy -0.2794 -0.1016) (xy 0.2794 -0.1016) (xy 0.2794 0.9906) (xy -0.2794 0.9906)
			)
			(stroke
				(width 0)
				(type default)
			)
			(fill no)
			(layer "F.CrtYd")
		)
		(fp_line
			(start 0.2794 -0.1016)
			(end -0.2794 -0.1016)
			(stroke
				(width 0.1)
				(type default)
			)
			(layer "F.Fab")
		)
		(fp_line
			(start -0.2794 -0.1016)
			(end -0.2794 0.9906)
			(stroke
				(width 0.1)
				(type default)
			)
			(layer "F.Fab")
		)
		(fp_line
			(start 0.2794 0.9906)
			(end 0.2794 -0.1016)
			(stroke
				(width 0.1)
				(type default)
			)
			(layer "F.Fab")
		)
		(fp_line
			(start -0.2794 0.9906)
			(end 0.2794 0.9906)
			(stroke
				(width 0.1)
				(type default)
			)
			(layer "F.Fab")
		)
		(pad "1" smd rect
			(at 0 0 90)
			(size 0.508 0.508)
			(layers "F.Cu" "F.Mask" "F.Paste")
			(net "PVCCIO_CPU1")
		)
		(pad "2" smd rect
			(at 0 0.889 90)
			(size 0.508 0.508)
			(layers "F.Cu" "F.Mask" "F.Paste")
			(net "PWRGD_CPU1_G")
		)
		(zone
			(layer "F.Cu")
			(hatch none 0.5)
			(connect_pads
				(clearance 0)
			)
			(min_thickness 0.25)
			(keepout
				(tracks allowed)
				(vias not_allowed)
				(pads allowed)
				(copperpour not_allowed)
				(footprints allowed)
			)
			(placement
				(enabled no)
				(sheetname "")
			)
			(fill
				(thermal_gap 0.5)
				(thermal_bridge_width 0.5)
				(island_removal_mode 0)
			)
			(polygon
				(pts
					(xy 116.5606 -73.533) (xy 116.5606 -74.041) (xy 116.9416 -74.041) (xy 116.9416 -73.533)
				)
			)
		)
		(zone
			(layer "F.Cu")
			(hatch none 0.5)
			(connect_pads
				(clearance 0)
			)
			(min_thickness 0.25)
			(keepout
				(tracks not_allowed)
				(vias allowed)
				(pads allowed)
				(copperpour not_allowed)
				(footprints allowed)
			)
			(placement
				(enabled no)
				(sheetname "")
			)
			(fill
				(thermal_gap 0.5)
				(thermal_bridge_width 0.5)
				(island_removal_mode 0)
			)
			(polygon
				(pts
					(xy 116.9416 -73.533) (xy 116.9416 -74.041) (xy 116.5606 -74.041) (xy 116.5606 -73.533)
				)
			)
		)
	)
	(footprint ""
		(layer "F.Cu")
		(at 406.6286 -61.6204 90)
		(property "Reference" "R8D35"
			(at 0 0 90)
			(layer "F.SilkS")
			(hide yes)
			(effects
				(font
					(size 1.27 1.27)
				)
			)
		)
		(property "Value" ""
			(at 0 0 90)
			(layer "F.Fab")
			(effects
				(font
					(size 1.27 1.27)
				)
			)
		)
		(duplicate_pad_numbers_are_jumpers no)
		(fp_poly
			(pts
				(xy -0.2794 -0.1016) (xy 0.2794 -0.1016) (xy 0.2794 0.9906) (xy -0.2794 0.9906)
			)
			(stroke
				(width 0)
				(type default)
			)
			(fill no)
			(layer "F.CrtYd")
		)
		(pad "1" smd rect
			(at 0 0 90)
			(size 0.508 0.508)
			(layers "F.Cu" "F.Mask" "F.Paste")
			(net "SPI_PCH_TPM_CS_N")
		)
		(pad "2" smd rect
			(at 0 0.889 90)
			(size 0.508 0.508)
			(layers "F.Cu" "F.Mask" "F.Paste")
			(net "SPI_PCH_TPM_CS_R_N")
		)
		(zone
			(layer "F.Cu")
			(hatch none 0.5)
			(connect_pads
				(clearance 0)
			)
			(min_thickness 0.25)
			(keepout
				(tracks allowed)
				(vias not_allowed)
				(pads allowed)
				(copperpour not_allowed)
				(footprints allowed)
			)
			(placement
				(enabled no)
				(sheetname "")
			)
			(fill
				(thermal_gap 0.5)
				(thermal_bridge_width 0.5)
				(island_removal_mode 0)
			)
			(polygon
				(pts
					(xy 406.8826 -61.3664) (xy 406.8826 -61.8744) (xy 407.2636 -61.8744) (xy 407.2636 -61.3664)
				)
			)
		)
		(zone
			(layer "F.Cu")
			(hatch none 0.5)
			(connect_pads
				(clearance 0)
			)
			(min_thickness 0.25)
			(keepout
				(tracks not_allowed)
				(vias allowed)
				(pads allowed)
				(copperpour not_allowed)
				(footprints allowed)
			)
			(placement
				(enabled no)
				(sheetname "")
			)
			(fill
				(thermal_gap 0.5)
				(thermal_bridge_width 0.5)
				(island_removal_mode 0)
			)
			(polygon
				(pts
					(xy 407.2636 -61.3664) (xy 407.2636 -61.8744) (xy 406.8826 -61.8744) (xy 406.8826 -61.3664)
				)
			)
		)
	)
	(footprint ""
		(layer "F.Cu")
		(at 83.856068 -149.8092 -90)
		(property "Reference" "C2A2"
			(at 1.848866 0.752348 270)
			(unlocked yes)
			(layer "F.SilkS")
			(effects
				(font
					(size 1.27 0.9652)
					(thickness 0.1524)
				)
			)
		)
		(property "Value" ""
			(at 0 0 270)
			(layer "F.Fab")
			(effects
				(font
					(size 1.27 1.27)
				)
			)
		)
		(duplicate_pad_numbers_are_jumpers no)
		(fp_rect
			(start -0.500126 1.598422)
			(end 0.500126 -0.201422)
			(stroke
				(width 0)
				(type default)
			)
			(fill no)
			(layer "F.CrtYd")
		)
		(fp_line
			(start -0.500126 1.598422)
			(end -0.500126 -0.201422)
			(stroke
				(width 0.1)
				(type default)
			)
			(layer "F.Fab")
		)
		(fp_line
			(start 0.500126 1.598422)
			(end -0.500126 1.598422)
			(stroke
				(width 0.1)
				(type default)
			)
			(layer "F.Fab")
		)
		(fp_line
			(start -0.500126 -0.201422)
			(end 0.500126 -0.201422)
			(stroke
				(width 0.1)
				(type default)
			)
			(layer "F.Fab")
		)
		(fp_line
			(start 0.500126 -0.201422)
			(end 0.500126 1.598422)
			(stroke
				(width 0.1)
				(type default)
			)
			(layer "F.Fab")
		)
		(pad "1" smd rect
			(at 0 0 180)
			(size 0.889 0.9906)
			(layers "F.Cu" "F.Mask" "F.Paste")
			(net "PVDDQ_KLM")
		)
		(pad "2" smd rect
			(at 0 1.397 180)
			(size 0.889 0.9906)
			(layers "F.Cu" "F.Mask" "F.Paste")
			(net "GND")
		)
		(zone
			(layer "F.Cu")
			(hatch none 0.5)
			(connect_pads
				(clearance 0)
			)
			(min_thickness 0.25)
			(keepout
				(tracks not_allowed)
				(vias allowed)
				(pads allowed)
				(copperpour not_allowed)
				(footprints allowed)
			)
			(placement
				(enabled no)
				(sheetname "")
			)
			(fill
				(thermal_gap 0.5)
				(thermal_bridge_width 0.5)
				(island_removal_mode 0)
			)
			(polygon
				(pts
					(xy 82.903568 -150.3045) (xy 82.903568 -149.3139) (xy 83.411568 -149.3139) (xy 83.411568 -150.3045)
				)
			)
		)
		(zone
			(layer "F.Cu")
			(hatch none 0.5)
			(connect_pads
				(clearance 0)
			)
			(min_thickness 0.25)
			(keepout
				(tracks allowed)
				(vias not_allowed)
				(pads allowed)
				(copperpour not_allowed)
				(footprints allowed)
			)
			(placement
				(enabled no)
				(sheetname "")
			)
			(fill
				(thermal_gap 0.5)
				(thermal_bridge_width 0.5)
				(island_removal_mode 0)
			)
			(polygon
				(pts
					(xy 82.903568 -150.3045) (xy 82.903568 -149.3139) (xy 83.411568 -149.3139) (xy 83.411568 -150.3045)
				)
			)
		)
	)
)
